# SCM (Grand Teton) — schematic netlist excerpt (pin names and nets, part order shuffled) for the footprints in the layout excerpt that follows; sources: Cadence DE-HDL packaged netlist, KiCad conversion of 12092022_DA0F0TMDCD0_F0T_Management_Board_D_brd_V3_OCP.brd

R467  Q_RES  2K 1% CHIP  pkg 0402LF  page 44 : A = PD_BIOS_MUX_EN_N ; B = GND
R278  Q_RES  0 5% EMPTY  pkg 0402LF  page 17 : A = P1V2_AUX ; B = P1V2_P1V0_I3C_VDDL1

(kicad_pcb
	(version 20260206)
	(generator "pcbnew")
	(generator_version "10.0")
	(general
		(thickness 1.6)
		(legacy_teardrops no)
	)
	(paper "A4")
	(title_block
		(title "12092022_DA0F0TMDCD0_F0T_Management_Board_D_brd_V3_OCP.brd")
		(comment 1 "Grand Teton / footprints 1157-1159 of 1440")
	)
	(layers
		(0 "F.Cu" signal "TOP")
		(4 "In1.Cu" signal "GND")
		(6 "In2.Cu" signal "IN1")
		(8 "In3.Cu" signal "GND1")
		(10 "In4.Cu" signal "IN2")
		(12 "In5.Cu" signal "VCC")
		(14 "In6.Cu" signal "VCC1")
		(16 "In7.Cu" signal "IN3")
		(18 "In8.Cu" signal "GND2")
		(20 "In9.Cu" signal "IN4")
		(22 "In10.Cu" signal "GND3")
		(2 "B.Cu" signal "BOTTOM")
		(9 "F.Adhes" user "F.Adhesive")
		(11 "B.Adhes" user "B.Adhesive")
		(13 "F.Paste" user "Package Geometry/Pastemask Top")
		(15 "B.Paste" user "Package Geometry/Pastemask Bottom")
		(5 "F.SilkS" user "Ref Des/Silkscreen Top")
		(7 "B.SilkS" user "Ref Des/Silkscreen Bottom")
		(1 "F.Mask" user "Board Geometry/Soldermask Top")
		(3 "B.Mask" user "Board Geometry/Soldermask Bottom")
		(17 "Dwgs.User" user "User.Drawings")
		(19 "Cmts.User" user "User.Comments")
		(21 "Eco1.User" user "User.Eco1")
		(23 "Eco2.User" user "User.Eco2")
		(25 "Edge.Cuts" user "Board Geometry/Outline")
		(27 "Margin" user)
		(31 "F.CrtYd" user "Package Geometry/Place Bound Top")
		(29 "B.CrtYd" user "Package Geometry/Place Bound Bottom")
		(35 "F.Fab" user "Ref Des/Assembly Top")
		(33 "B.Fab" user "Ref Des/Assembly Bottom")
	)
	(footprint ""
		(layer "B.Cu")
		(at 38.7223 -52.779676 -90)
		(property "Reference" "R278"
			(at 0 0 90)
			(layer "B.SilkS")
			(hide yes)
			(effects
				(font
					(size 1.27 1.27)
				)
				(justify mirror)
			)
		)
		(property "Value" ""
			(at 0 0 90)
			(layer "B.Fab")
			(effects
				(font
					(size 1.27 1.27)
				)
				(justify mirror)
			)
		)
		(duplicate_pad_numbers_are_jumpers no)
		(fp_line
			(start -0.7874 0.4064)
			(end 0.7874 0.4064)
			(stroke
				(width 0.1524)
				(type default)
			)
			(layer "B.SilkS")
		)
		(fp_line
			(start 0.7874 0.4064)
			(end 0.7874 -0.4064)
			(stroke
				(width 0.1524)
				(type default)
			)
			(layer "B.SilkS")
		)
		(fp_line
			(start -0.7874 -0.4064)
			(end -0.7874 0.4064)
			(stroke
				(width 0.1524)
				(type default)
			)
			(layer "B.SilkS")
		)
		(fp_line
			(start 0.7874 -0.4064)
			(end -0.7874 -0.4064)
			(stroke
				(width 0.1524)
				(type default)
			)
			(layer "B.SilkS")
		)
		(fp_line
			(start -0.67945 0.3048)
			(end -0.120396 0.3048)
			(stroke
				(width 0.1)
				(type default)
			)
			(layer "B.Fab")
		)
		(fp_line
			(start -0.120396 0.3048)
			(end -0.120396 0.2794)
			(stroke
				(width 0.1)
				(type default)
			)
			(layer "B.Fab")
		)
		(fp_line
			(start 0.12065 0.3048)
			(end 0.67945 0.3048)
			(stroke
				(width 0.1)
				(type default)
			)
			(layer "B.Fab")
		)
		(fp_line
			(start 0.67945 0.3048)
			(end 0.67945 -0.305054)
			(stroke
				(width 0.1)
				(type default)
			)
			(layer "B.Fab")
		)
		(fp_line
			(start -0.120396 0.2794)
			(end 0.12065 0.2794)
			(stroke
				(width 0.1)
				(type default)
			)
			(layer "B.Fab")
		)
		(fp_line
			(start 0.12065 0.2794)
			(end 0.12065 0.3048)
			(stroke
				(width 0.1)
				(type default)
			)
			(layer "B.Fab")
		)
		(fp_line
			(start -0.12065 -0.2794)
			(end -0.12065 -0.3048)
			(stroke
				(width 0.1)
				(type default)
			)
			(layer "B.Fab")
		)
		(fp_line
			(start 0.12065 -0.2794)
			(end -0.12065 -0.2794)
			(stroke
				(width 0.1)
				(type default)
			)
			(layer "B.Fab")
		)
		(fp_line
			(start -0.67945 -0.3048)
			(end -0.67945 0.3048)
			(stroke
				(width 0.1)
				(type default)
			)
			(layer "B.Fab")
		)
		(fp_line
			(start -0.12065 -0.3048)
			(end -0.67945 -0.3048)
			(stroke
				(width 0.1)
				(type default)
			)
			(layer "B.Fab")
		)
		(fp_line
			(start 0.12065 -0.305054)
			(end 0.12065 -0.2794)
			(stroke
				(width 0.1)
				(type default)
			)
			(layer "B.Fab")
		)
		(fp_line
			(start 0.67945 -0.305054)
			(end 0.12065 -0.305054)
			(stroke
				(width 0.1)
				(type default)
			)
			(layer "B.Fab")
		)
		(pad "1" smd circle
			(at 0.40005 0 90)
			(size 0 0)
			(layers "B.Cu" "B.Mask" "B.Paste")
			(net "P1V2_AUX")
		)
		(pad "2" smd circle
			(at -0.40005 0 90)
			(size 0 0)
			(layers "B.Cu" "B.Mask" "B.Paste")
			(net "P1V2_P1V0_I3C_VDDL1")
		)
	)
	(footprint ""
		(layer "B.Cu")
		(at 37.4015 -100.965)
		(property "Reference" "R467"
			(at 0 0 0)
			(layer "B.SilkS")
			(hide yes)
			(effects
				(font
					(size 1.27 1.27)
				)
				(justify mirror)
			)
		)
		(property "Value" ""
			(at 0 0 0)
			(layer "B.Fab")
			(effects
				(font
					(size 1.27 1.27)
				)
				(justify mirror)
			)
		)
		(duplicate_pad_numbers_are_jumpers no)
		(fp_line
			(start -0.7874 -0.4064)
			(end -0.7874 0.4064)
			(stroke
				(width 0.1524)
				(type default)
			)
			(layer "B.SilkS")
		)
		(fp_line
			(start -0.7874 0.4064)
			(end 0.7874 0.4064)
			(stroke
				(width 0.1524)
				(type default)
			)
			(layer "B.SilkS")
		)
		(fp_line
			(start 0.7874 -0.4064)
			(end -0.7874 -0.4064)
			(stroke
				(width 0.1524)
				(type default)
			)
			(layer "B.SilkS")
		)
		(fp_line
			(start 0.7874 0.4064)
			(end 0.7874 -0.4064)
			(stroke
				(width 0.1524)
				(type default)
			)
			(layer "B.SilkS")
		)
		(fp_line
			(start -0.67945 -0.3048)
			(end -0.67945 0.3048)
			(stroke
				(width 0.1)
				(type default)
			)
			(layer "B.Fab")
		)
		(fp_line
			(start -0.67945 0.3048)
			(end -0.120396 0.3048)
			(stroke
				(width 0.1)
				(type default)
			)
			(layer "B.Fab")
		)
		(fp_line
			(start -0.12065 -0.3048)
			(end -0.67945 -0.3048)
			(stroke
				(width 0.1)
				(type default)
			)
			(layer "B.Fab")
		)
		(fp_line
			(start -0.12065 -0.2794)
			(end -0.12065 -0.3048)
			(stroke
				(width 0.1)
				(type default)
			)
			(layer "B.Fab")
		)
		(fp_line
			(start -0.120396 0.2794)
			(end 0.12065 0.2794)
			(stroke
				(width 0.1)
				(type default)
			)
			(layer "B.Fab")
		)
		(fp_line
			(start -0.120396 0.3048)
			(end -0.120396 0.2794)
			(stroke
				(width 0.1)
				(type default)
			)
			(layer "B.Fab")
		)
		(fp_line
			(start 0.12065 -0.305054)
			(end 0.12065 -0.2794)
			(stroke
				(width 0.1)
				(type default)
			)
			(layer "B.Fab")
		)
		(fp_line
			(start 0.12065 -0.2794)
			(end -0.12065 -0.2794)
			(stroke
				(width 0.1)
				(type default)
			)
			(layer "B.Fab")
		)
		(fp_line
			(start 0.12065 0.2794)
			(end 0.12065 0.3048)
			(stroke
				(width 0.1)
				(type default)
			)
			(layer "B.Fab")
		)
		(fp_line
			(start 0.12065 0.3048)
			(end 0.67945 0.3048)
			(stroke
				(width 0.1)
				(type default)
			)
			(layer "B.Fab")
		)
		(fp_line
			(start 0.67945 -0.305054)
			(end 0.12065 -0.305054)
			(stroke
				(width 0.1)
				(type default)
			)
			(layer "B.Fab")
		)
		(fp_line
			(start 0.67945 0.3048)
			(end 0.67945 -0.305054)
			(stroke
				(width 0.1)
				(type default)
			)
			(layer "B.Fab")
		)
		(pad "1" smd circle
			(at 0.40005 0 180)
			(size 0 0)
			(layers "B.Cu" "B.Mask" "B.Paste")
			(net "PD_BIOS_MUX_EN_N")
		)
		(pad "2" smd circle
			(at -0.40005 0 180)
			(size 0 0)
			(layers "B.Cu" "B.Mask" "B.Paste")
			(net "GND")
		)
	)
	(footprint ""
		(layer "B.Cu")
		(at 68.6054 -50.292)
		(property "Reference" ""
			(at 0 0 0)
			(layer "B.SilkS")
			(hide yes)
			(effects
				(font
					(size 1.27 1.27)
				)
				(justify mirror)
			)
		)
		(property "Value" ""
			(at 0 0 0)
			(layer "B.Fab")
			(effects
				(font
					(size 1.27 1.27)
				)
				(justify mirror)
			)
		)
		(duplicate_pad_numbers_are_jumpers no)
		(pad "1" smd circle
			(at 0 0 180)
			(size 0.9906 0.9906)
			(layers "B.Cu" "B.Mask" "B.Paste")
			(net "Net_134")
		)
		(zone
			(layer "B.Cu")
			(hatch none 0.5)
			(connect_pads
				(clearance 0)
			)
			(min_thickness 0.25)
			(keepout
				(tracks not_allowed)
				(vias allowed)
				(pads allowed)
				(copperpour not_allowed)
				(footprints allowed)
			)
			(placement
				(enabled no)
				(sheetname "")
			)
			(fill
				(thermal_gap 0.5)
				(thermal_bridge_width 0.5)
				(island_removal_mode 0)
			)
			(polygon
				(pts
					(arc
						(start 70.231 -50.292)
						(mid 66.9798 -50.292)
						(end 70.231 -50.292)
					)
				)
			)
		)
	)
)
